(kicad_pcb
	(version 20260206)
	(generator "pcbnew")
	(generator_version "10.0")
	(general
		(thickness 1.6)
		(legacy_teardrops no)
	)
	(paper "A4")
	(title_block
		(title "04192023_DAF0TMB3IC0_F0TG_MB_C_brd_V02_OCP.brd")
		(comment 1 "Grand Teton / footprints 3691-3697 of 8354")
	)
	(layers
		(0 "F.Cu" signal "TOP")
		(4 "In1.Cu" signal "GND")
		(6 "In2.Cu" signal "IN1")
		(8 "In3.Cu" signal "GND1")
		(10 "In4.Cu" signal "IN2")
		(12 "In5.Cu" signal "GND2")
		(14 "In6.Cu" signal "IN3")
		(16 "In7.Cu" signal "GND3")
		(18 "In8.Cu" signal "VCC")
		(20 "In9.Cu" signal "VCC1")
		(22 "In10.Cu" signal "GND4")
		(24 "In11.Cu" signal "IN4")
		(26 "In12.Cu" signal "GND5")
		(28 "In13.Cu" signal "IN5")
		(30 "In14.Cu" signal "GND6")
		(32 "In15.Cu" signal "IN6")
		(34 "In16.Cu" signal "GND7")
		(2 "B.Cu" signal "BOTTOM")
		(9 "F.Adhes" user "F.Adhesive")
		(11 "B.Adhes" user "B.Adhesive")
		(13 "F.Paste" user "Package Geometry/Pastemask Top")
		(15 "B.Paste" user "Package Geometry/Pastemask Bottom")
		(5 "F.SilkS" user "Ref Des/Silkscreen Top")
		(7 "B.SilkS" user "Ref Des/Silkscreen Bottom")
		(1 "F.Mask" user "Board Geometry/Soldermask Top")
		(3 "B.Mask" user "Board Geometry/Soldermask Bottom")
		(17 "Dwgs.User" user "User.Drawings")
		(19 "Cmts.User" user "User.Comments")
		(21 "Eco1.User" user "User.Eco1")
		(23 "Eco2.User" user "User.Eco2")
		(25 "Edge.Cuts" user "Board Geometry/Outline")
		(27 "Margin" user)
		(31 "F.CrtYd" user "Package Geometry/Place Bound Top")
		(29 "B.CrtYd" user "Package Geometry/Place Bound Bottom")
		(35 "F.Fab" user "Ref Des/Assembly Top")
		(33 "B.Fab" user "Ref Des/Assembly Bottom")
	)
	(footprint ""
		(layer "F.Cu")
		(at 200.952608 -116.673376)
		(property "Reference" "R800"
			(at 0 0 0)
			(layer "F.SilkS")
			(hide yes)
			(effects
				(font
					(size 1.27 1.27)
				)
			)
		)
		(property "Value" ""
			(at 0 0 0)
			(layer "F.Fab")
			(effects
				(font
					(size 1.27 1.27)
				)
			)
		)
		(duplicate_pad_numbers_are_jumpers no)
		(fp_line
			(start -0.7874 -0.4064)
			(end 0.7874 -0.4064)
			(stroke
				(width 0.1524)
				(type default)
			)
			(layer "F.SilkS")
		)
		(fp_line
			(start -0.7874 0.4064)
			(end -0.7874 -0.4064)
			(stroke
				(width 0.1524)
				(type default)
			)
			(layer "F.SilkS")
		)
		(fp_line
			(start 0.7874 -0.4064)
			(end 0.7874 0.4064)
			(stroke
				(width 0.1524)
				(type default)
			)
			(layer "F.SilkS")
		)
		(fp_line
			(start 0.7874 0.4064)
			(end -0.7874 0.4064)
			(stroke
				(width 0.1524)
				(type default)
			)
			(layer "F.SilkS")
		)
		(fp_line
			(start -0.67945 -0.305054)
			(end -0.12065 -0.305054)
			(stroke
				(width 0.1)
				(type default)
			)
			(layer "F.Fab")
		)
		(fp_line
			(start -0.67945 0.3048)
			(end -0.67945 -0.305054)
			(stroke
				(width 0.1)
				(type default)
			)
			(layer "F.Fab")
		)
		(fp_line
			(start -0.12065 -0.305054)
			(end -0.12065 -0.2794)
			(stroke
				(width 0.1)
				(type default)
			)
			(layer "F.Fab")
		)
		(fp_line
			(start -0.12065 -0.2794)
			(end 0.12065 -0.2794)
			(stroke
				(width 0.1)
				(type default)
			)
			(layer "F.Fab")
		)
		(fp_line
			(start -0.12065 0.2794)
			(end -0.12065 0.3048)
			(stroke
				(width 0.1)
				(type default)
			)
			(layer "F.Fab")
		)
		(fp_line
			(start -0.12065 0.3048)
			(end -0.67945 0.3048)
			(stroke
				(width 0.1)
				(type default)
			)
			(layer "F.Fab")
		)
		(fp_line
			(start 0.120396 0.2794)
			(end -0.12065 0.2794)
			(stroke
				(width 0.1)
				(type default)
			)
			(layer "F.Fab")
		)
		(fp_line
			(start 0.120396 0.3048)
			(end 0.120396 0.2794)
			(stroke
				(width 0.1)
				(type default)
			)
			(layer "F.Fab")
		)
		(fp_line
			(start 0.12065 -0.3048)
			(end 0.67945 -0.3048)
			(stroke
				(width 0.1)
				(type default)
			)
			(layer "F.Fab")
		)
		(fp_line
			(start 0.12065 -0.2794)
			(end 0.12065 -0.3048)
			(stroke
				(width 0.1)
				(type default)
			)
			(layer "F.Fab")
		)
		(fp_line
			(start 0.67945 -0.3048)
			(end 0.67945 0.3048)
			(stroke
				(width 0.1)
				(type default)
			)
			(layer "F.Fab")
		)
		(fp_line
			(start 0.67945 0.3048)
			(end 0.120396 0.3048)
			(stroke
				(width 0.1)
				(type default)
			)
			(layer "F.Fab")
		)
		(pad "1" smd circle
			(at -0.40005 0)
			(size 0 0)
			(layers "F.Cu" "F.Mask" "F.Paste")
			(net "RST_PERST_E1S_0_N")
		)
		(pad "2" smd circle
			(at 0.40005 0)
			(size 0 0)
			(layers "F.Cu" "F.Mask" "F.Paste")
			(net "GND")
		)
	)
	(footprint ""
		(layer "F.Cu")
		(at 125.992636 -59.182 180)
		(property "Reference" "R1739"
			(at 0 0 180)
			(layer "F.SilkS")
			(hide yes)
			(effects
				(font
					(size 1.27 1.27)
				)
			)
		)
		(property "Value" ""
			(at 0 0 180)
			(layer "F.Fab")
			(effects
				(font
					(size 1.27 1.27)
				)
			)
		)
		(duplicate_pad_numbers_are_jumpers no)
		(fp_line
			(start 0.7874 0.4064)
			(end -0.7874 0.4064)
			(stroke
				(width 0.1524)
				(type default)
			)
			(layer "F.SilkS")
		)
		(fp_line
			(start 0.7874 -0.4064)
			(end 0.7874 0.4064)
			(stroke
				(width 0.1524)
				(type default)
			)
			(layer "F.SilkS")
		)
		(fp_line
			(start -0.7874 0.4064)
			(end -0.7874 -0.4064)
			(stroke
				(width 0.1524)
				(type default)
			)
			(layer "F.SilkS")
		)
		(fp_line
			(start -0.7874 -0.4064)
			(end 0.7874 -0.4064)
			(stroke
				(width 0.1524)
				(type default)
			)
			(layer "F.SilkS")
		)
		(fp_line
			(start 0.67945 0.3048)
			(end 0.120396 0.3048)
			(stroke
				(width 0.1)
				(type default)
			)
			(layer "F.Fab")
		)
		(fp_line
			(start 0.67945 -0.3048)
			(end 0.67945 0.3048)
			(stroke
				(width 0.1)
				(type default)
			)
			(layer "F.Fab")
		)
		(fp_line
			(start 0.12065 -0.2794)
			(end 0.12065 -0.3048)
			(stroke
				(width 0.1)
				(type default)
			)
			(layer "F.Fab")
		)
		(fp_line
			(start 0.12065 -0.3048)
			(end 0.67945 -0.3048)
			(stroke
				(width 0.1)
				(type default)
			)
			(layer "F.Fab")
		)
		(fp_line
			(start 0.120396 0.3048)
			(end 0.120396 0.2794)
			(stroke
				(width 0.1)
				(type default)
			)
			(layer "F.Fab")
		)
		(fp_line
			(start 0.120396 0.2794)
			(end -0.12065 0.2794)
			(stroke
				(width 0.1)
				(type default)
			)
			(layer "F.Fab")
		)
		(fp_line
			(start -0.12065 0.3048)
			(end -0.67945 0.3048)
			(stroke
				(width 0.1)
				(type default)
			)
			(layer "F.Fab")
		)
		(fp_line
			(start -0.12065 0.2794)
			(end -0.12065 0.3048)
			(stroke
				(width 0.1)
				(type default)
			)
			(layer "F.Fab")
		)
		(fp_line
			(start -0.12065 -0.2794)
			(end 0.12065 -0.2794)
			(stroke
				(width 0.1)
				(type default)
			)
			(layer "F.Fab")
		)
		(fp_line
			(start -0.12065 -0.305054)
			(end -0.12065 -0.2794)
			(stroke
				(width 0.1)
				(type default)
			)
			(layer "F.Fab")
		)
		(fp_line
			(start -0.67945 0.3048)
			(end -0.67945 -0.305054)
			(stroke
				(width 0.1)
				(type default)
			)
			(layer "F.Fab")
		)
		(fp_line
			(start -0.67945 -0.305054)
			(end -0.12065 -0.305054)
			(stroke
				(width 0.1)
				(type default)
			)
			(layer "F.Fab")
		)
		(pad "1" smd circle
			(at -0.40005 0 180)
			(size 0 0)
			(layers "F.Cu" "F.Mask" "F.Paste")
			(net "JTAG_SCM_MUX_R_TDO")
		)
		(pad "2" smd circle
			(at 0.40005 0 180)
			(size 0 0)
			(layers "F.Cu" "F.Mask" "F.Paste")
			(net "JTAG_SCM_MUX_TDO")
		)
	)
	(footprint ""
		(layer "F.Cu")
		(at 310.056022 -37.017706 180)
		(property "Reference" "C1767"
			(at 0 0 180)
			(layer "F.SilkS")
			(hide yes)
			(effects
				(font
					(size 1.27 1.27)
				)
			)
		)
		(property "Value" ""
			(at 0 0 180)
			(layer "F.Fab")
			(effects
				(font
					(size 1.27 1.27)
				)
			)
		)
		(duplicate_pad_numbers_are_jumpers no)
		(fp_line
			(start 1.524 0.762)
			(end -1.524 0.762)
			(stroke
				(width 0.1524)
				(type default)
			)
			(layer "F.SilkS")
		)
		(fp_line
			(start 1.524 -0.762)
			(end 1.524 0.762)
			(stroke
				(width 0.1524)
				(type default)
			)
			(layer "F.SilkS")
		)
		(fp_line
			(start -1.524 0.762)
			(end -1.524 -0.762)
			(stroke
				(width 0.1524)
				(type default)
			)
			(layer "F.SilkS")
		)
		(fp_line
			(start -1.524 -0.762)
			(end 1.524 -0.762)
			(stroke
				(width 0.1524)
				(type default)
			)
			(layer "F.SilkS")
		)
		(fp_line
			(start 1.1049 0.724916)
			(end 1.1049 -0.724916)
			(stroke
				(width 0.1)
				(type default)
			)
			(layer "F.Fab")
		)
		(fp_line
			(start 1.1049 -0.724916)
			(end -1.1049 -0.724916)
			(stroke
				(width 0.1)
				(type default)
			)
			(layer "F.Fab")
		)
		(fp_line
			(start -1.1049 0.724916)
			(end 1.1049 0.724916)
			(stroke
				(width 0.1)
				(type default)
			)
			(layer "F.Fab")
		)
		(fp_line
			(start -1.1049 -0.724916)
			(end -1.1049 0.724916)
			(stroke
				(width 0.1)
				(type default)
			)
			(layer "F.Fab")
		)
		(pad "1" smd rect
			(at -0.889 0)
			(size 1.016 1.27)
			(layers "F.Cu" "F.Mask" "F.Paste")
			(net "MAX11617_VREF")
		)
		(pad "2" smd rect
			(at 0.889 0)
			(size 1.016 1.27)
			(layers "F.Cu" "F.Mask" "F.Paste")
			(net "GND")
		)
	)
	(footprint ""
		(layer "F.Cu")
		(at 405.478742 -416.899344 -90)
		(property "Reference" "C6587"
			(at 0 0 270)
			(layer "F.SilkS")
			(hide yes)
			(effects
				(font
					(size 1.27 1.27)
				)
			)
		)
		(property "Value" ""
			(at 0 0 270)
			(layer "F.Fab")
			(effects
				(font
					(size 1.27 1.27)
				)
			)
		)
		(duplicate_pad_numbers_are_jumpers no)
		(fp_line
			(start -0.299974 0.150114)
			(end -0.299974 -0.150114)
			(stroke
				(width 0.1)
				(type default)
			)
			(layer "F.Fab")
		)
		(fp_line
			(start 0.299974 0.150114)
			(end -0.299974 0.150114)
			(stroke
				(width 0.1)
				(type default)
			)
			(layer "F.Fab")
		)
		(fp_line
			(start -0.299974 -0.150114)
			(end 0.299974 -0.150114)
			(stroke
				(width 0.1)
				(type default)
			)
			(layer "F.Fab")
		)
		(fp_line
			(start 0.299974 -0.150114)
			(end 0.299974 0.150114)
			(stroke
				(width 0.1)
				(type default)
			)
			(layer "F.Fab")
		)
		(pad "1" smd rect
			(at -0.2667 0 270)
			(size 0.3048 0.381)
			(layers "F.Cu" "F.Mask" "F.Paste")
			(net "P5E_CPU0_P2_TX_BUF_C_DP<11>")
		)
		(pad "2" smd rect
			(at 0.2667 0 270)
			(size 0.3048 0.381)
			(layers "F.Cu" "F.Mask" "F.Paste")
			(net "P5E_CPU0_P2_TX_BUF_DP<11>")
		)
	)
	(footprint ""
		(layer "F.Cu")
		(at 183.007 -140.172948 90)
		(property "Reference" "R1287"
			(at 0 0 90)
			(layer "F.SilkS")
			(hide yes)
			(effects
				(font
					(size 1.27 1.27)
				)
			)
		)
		(property "Value" ""
			(at 0 0 90)
			(layer "F.Fab")
			(effects
				(font
					(size 1.27 1.27)
				)
			)
		)
		(duplicate_pad_numbers_are_jumpers no)
		(fp_line
			(start 0.7874 -0.4064)
			(end 0.7874 0.4064)
			(stroke
				(width 0.1524)
				(type default)
			)
			(layer "F.SilkS")
		)
		(fp_line
			(start -0.7874 -0.4064)
			(end 0.7874 -0.4064)
			(stroke
				(width 0.1524)
				(type default)
			)
			(layer "F.SilkS")
		)
		(fp_line
			(start 0.7874 0.4064)
			(end -0.7874 0.4064)
			(stroke
				(width 0.1524)
				(type default)
			)
			(layer "F.SilkS")
		)
		(fp_line
			(start -0.7874 0.4064)
			(end -0.7874 -0.4064)
			(stroke
				(width 0.1524)
				(type default)
			)
			(layer "F.SilkS")
		)
		(fp_line
			(start -0.12065 -0.305054)
			(end -0.12065 -0.2794)
			(stroke
				(width 0.1)
				(type default)
			)
			(layer "F.Fab")
		)
		(fp_line
			(start -0.67945 -0.305054)
			(end -0.12065 -0.305054)
			(stroke
				(width 0.1)
				(type default)
			)
			(layer "F.Fab")
		)
		(fp_line
			(start 0.67945 -0.3048)
			(end 0.67945 0.3048)
			(stroke
				(width 0.1)
				(type default)
			)
			(layer "F.Fab")
		)
		(fp_line
			(start 0.12065 -0.3048)
			(end 0.67945 -0.3048)
			(stroke
				(width 0.1)
				(type default)
			)
			(layer "F.Fab")
		)
		(fp_line
			(start 0.12065 -0.2794)
			(end 0.12065 -0.3048)
			(stroke
				(width 0.1)
				(type default)
			)
			(layer "F.Fab")
		)
		(fp_line
			(start -0.12065 -0.2794)
			(end 0.12065 -0.2794)
			(stroke
				(width 0.1)
				(type default)
			)
			(layer "F.Fab")
		)
		(fp_line
			(start 0.120396 0.2794)
			(end -0.12065 0.2794)
			(stroke
				(width 0.1)
				(type default)
			)
			(layer "F.Fab")
		)
		(fp_line
			(start -0.12065 0.2794)
			(end -0.12065 0.3048)
			(stroke
				(width 0.1)
				(type default)
			)
			(layer "F.Fab")
		)
		(fp_line
			(start 0.67945 0.3048)
			(end 0.120396 0.3048)
			(stroke
				(width 0.1)
				(type default)
			)
			(layer "F.Fab")
		)
		(fp_line
			(start 0.120396 0.3048)
			(end 0.120396 0.2794)
			(stroke
				(width 0.1)
				(type default)
			)
			(layer "F.Fab")
		)
		(fp_line
			(start -0.12065 0.3048)
			(end -0.67945 0.3048)
			(stroke
				(width 0.1)
				(type default)
			)
			(layer "F.Fab")
		)
		(fp_line
			(start -0.67945 0.3048)
			(end -0.67945 -0.305054)
			(stroke
				(width 0.1)
				(type default)
			)
			(layer "F.Fab")
		)
		(pad "1" smd circle
			(at -0.40005 0 90)
			(size 0 0)
			(layers "F.Cu" "F.Mask" "F.Paste")
			(net "FM_P0_PCC0_N")
		)
		(pad "2" smd circle
			(at 0.40005 0 90)
			(size 0 0)
			(layers "F.Cu" "F.Mask" "F.Paste")
			(net "PVDD18_S5_P0")
		)
	)
	(footprint ""
		(layer "F.Cu")
		(at 237.843822 -290.341812 90)
		(property "Reference" "PC6515"
			(at 0 0 90)
			(layer "F.SilkS")
			(hide yes)
			(effects
				(font
					(size 1.27 1.27)
				)
			)
		)
		(property "Value" ""
			(at 0 0 90)
			(layer "F.Fab")
			(effects
				(font
					(size 1.27 1.27)
				)
			)
		)
		(duplicate_pad_numbers_are_jumpers no)
		(fp_line
			(start 0.7874 -0.4064)
			(end 0.7874 0.4064)
			(stroke
				(width 0.1524)
				(type default)
			)
			(layer "F.SilkS")
		)
		(fp_line
			(start -0.7874 -0.4064)
			(end 0.7874 -0.4064)
			(stroke
				(width 0.1524)
				(type default)
			)
			(layer "F.SilkS")
		)
		(fp_line
			(start 0.7874 0.4064)
			(end -0.7874 0.4064)
			(stroke
				(width 0.1524)
				(type default)
			)
			(layer "F.SilkS")
		)
		(fp_line
			(start -0.7874 0.4064)
			(end -0.7874 -0.4064)
			(stroke
				(width 0.1524)
				(type default)
			)
			(layer "F.SilkS")
		)
		(fp_line
			(start -0.12065 -0.305054)
			(end -0.12065 -0.2794)
			(stroke
				(width 0.1)
				(type default)
			)
			(layer "F.Fab")
		)
		(fp_line
			(start -0.67945 -0.305054)
			(end -0.12065 -0.305054)
			(stroke
				(width 0.1)
				(type default)
			)
			(layer "F.Fab")
		)
		(fp_line
			(start 0.67945 -0.3048)
			(end 0.67945 0.3048)
			(stroke
				(width 0.1)
				(type default)
			)
			(layer "F.Fab")
		)
		(fp_line
			(start 0.12065 -0.3048)
			(end 0.67945 -0.3048)
			(stroke
				(width 0.1)
				(type default)
			)
			(layer "F.Fab")
		)
		(fp_line
			(start 0.12065 -0.2794)
			(end 0.12065 -0.3048)
			(stroke
				(width 0.1)
				(type default)
			)
			(layer "F.Fab")
		)
		(fp_line
			(start -0.12065 -0.2794)
			(end 0.12065 -0.2794)
			(stroke
				(width 0.1)
				(type default)
			)
			(layer "F.Fab")
		)
		(fp_line
			(start 0.120396 0.2794)
			(end -0.12065 0.2794)
			(stroke
				(width 0.1)
				(type default)
			)
			(layer "F.Fab")
		)
		(fp_line
			(start -0.12065 0.2794)
			(end -0.12065 0.3048)
			(stroke
				(width 0.1)
				(type default)
			)
			(layer "F.Fab")
		)
		(fp_line
			(start 0.67945 0.3048)
			(end 0.120396 0.3048)
			(stroke
				(width 0.1)
				(type default)
			)
			(layer "F.Fab")
		)
		(fp_line
			(start 0.120396 0.3048)
			(end 0.120396 0.2794)
			(stroke
				(width 0.1)
				(type default)
			)
			(layer "F.Fab")
		)
		(fp_line
			(start -0.12065 0.3048)
			(end -0.67945 0.3048)
			(stroke
				(width 0.1)
				(type default)
			)
			(layer "F.Fab")
		)
		(fp_line
			(start -0.67945 0.3048)
			(end -0.67945 -0.305054)
			(stroke
				(width 0.1)
				(type default)
			)
			(layer "F.Fab")
		)
		(pad "1" smd circle
			(at -0.40005 0 90)
			(size 0 0)
			(layers "F.Cu" "F.Mask" "F.Paste")
			(net "P1V8_RETIMER_CPU0_FB")
		)
		(pad "2" smd circle
			(at 0.40005 0 90)
			(size 0 0)
			(layers "F.Cu" "F.Mask" "F.Paste")
			(net "P1V8_CPU0_RT_1D")
		)
	)
	(footprint ""
		(layer "F.Cu")
		(at 15.55115 -68.128642)
		(property "Reference" "R1191"
			(at 0 0 0)
			(layer "F.SilkS")
			(hide yes)
			(effects
				(font
					(size 1.27 1.27)
				)
			)
		)
		(property "Value" ""
			(at 0 0 0)
			(layer "F.Fab")
			(effects
				(font
					(size 1.27 1.27)
				)
			)
		)
		(duplicate_pad_numbers_are_jumpers no)
		(fp_line
			(start -0.7874 -0.4064)
			(end 0.7874 -0.4064)
			(stroke
				(width 0.1524)
				(type default)
			)
			(layer "F.SilkS")
		)
		(fp_line
			(start -0.7874 0.4064)
			(end -0.7874 -0.4064)
			(stroke
				(width 0.1524)
				(type default)
			)
			(layer "F.SilkS")
		)
		(fp_line
			(start 0.7874 -0.4064)
			(end 0.7874 0.4064)
			(stroke
				(width 0.1524)
				(type default)
			)
			(layer "F.SilkS")
		)
		(fp_line
			(start 0.7874 0.4064)
			(end -0.7874 0.4064)
			(stroke
				(width 0.1524)
				(type default)
			)
			(layer "F.SilkS")
		)
		(fp_line
			(start -0.67945 -0.305054)
			(end -0.12065 -0.305054)
			(stroke
				(width 0.1)
				(type default)
			)
			(layer "F.Fab")
		)
		(fp_line
			(start -0.67945 0.3048)
			(end -0.67945 -0.305054)
			(stroke
				(width 0.1)
				(type default)
			)
			(layer "F.Fab")
		)
		(fp_line
			(start -0.12065 -0.305054)
			(end -0.12065 -0.2794)
			(stroke
				(width 0.1)
				(type default)
			)
			(layer "F.Fab")
		)
		(fp_line
			(start -0.12065 -0.2794)
			(end 0.12065 -0.2794)
			(stroke
				(width 0.1)
				(type default)
			)
			(layer "F.Fab")
		)
		(fp_line
			(start -0.12065 0.2794)
			(end -0.12065 0.3048)
			(stroke
				(width 0.1)
				(type default)
			)
			(layer "F.Fab")
		)
		(fp_line
			(start -0.12065 0.3048)
			(end -0.67945 0.3048)
			(stroke
				(width 0.1)
				(type default)
			)
			(layer "F.Fab")
		)
		(fp_line
			(start 0.120396 0.2794)
			(end -0.12065 0.2794)
			(stroke
				(width 0.1)
				(type default)
			)
			(layer "F.Fab")
		)
		(fp_line
			(start 0.120396 0.3048)
			(end 0.120396 0.2794)
			(stroke
				(width 0.1)
				(type default)
			)
			(layer "F.Fab")
		)
		(fp_line
			(start 0.12065 -0.3048)
			(end 0.67945 -0.3048)
			(stroke
				(width 0.1)
				(type default)
			)
			(layer "F.Fab")
		)
		(fp_line
			(start 0.12065 -0.2794)
			(end 0.12065 -0.3048)
			(stroke
				(width 0.1)
				(type default)
			)
			(layer "F.Fab")
		)
		(fp_line
			(start 0.67945 -0.3048)
			(end 0.67945 0.3048)
			(stroke
				(width 0.1)
				(type default)
			)
			(layer "F.Fab")
		)
		(fp_line
			(start 0.67945 0.3048)
			(end 0.120396 0.3048)
			(stroke
				(width 0.1)
				(type default)
			)
			(layer "F.Fab")
		)
		(pad "1" smd circle
			(at -0.40005 0)
			(size 0 0)
			(layers "F.Cu" "F.Mask" "F.Paste")
			(net "HP_LVC3_OCP_V3_2_PRSNT2_N_R")
		)
		(pad "2" smd circle
			(at 0.40005 0)
			(size 0 0)
			(layers "F.Cu" "F.Mask" "F.Paste")
			(net "HP_LVC3_OCP_V3_2_PRSNT2_N")
		)
	)
)
